# TIMECARD (Time Appliance Project (Time Card)) — schematic netlist excerpt (pin names and nets, part order shuffled) for the footprints in the layout excerpt that follows; sources: Cadence DE-HDL packaged netlist, KiCad conversion of R4006-B0001-02_R01.brd

SP52  NULL  pkg DUMMY  page 34
C281  CAPACITOR  0.1UF 25V 10%  pkg SMC_0402R_H022  page 20 : \1\ = VDD_BNO085 ; \2\ = SG
SP58  NULL  pkg DUMMY  page 34
CR2  DIODE_2F  pkg SMC_CR_067X049_V1  page 33 : A = XP5R0V_FT4232 ; C = UNNAMED_525_CAPACITOR_I7_1

(kicad_pcb
	(version 20260206)
	(generator "pcbnew")
	(generator_version "10.0")
	(general
		(thickness 1.6)
		(legacy_teardrops no)
	)
	(paper "A4")
	(title_block
		(title "timecard-production-celestica-r4006 — R4006-B0001-02_R01.brd")
		(comment 1 "Time Appliance Project (Time Card) / footprints 506-509 of 1113")
	)
	(layers
		(0 "F.Cu" signal "TOP")
		(4 "In1.Cu" signal "L02_GND1")
		(6 "In2.Cu" signal "L03_SIG1")
		(8 "In3.Cu" signal "L04_GND2")
		(10 "In4.Cu" signal "L05_VCC1")
		(12 "In5.Cu" signal "L06_VCC2")
		(14 "In6.Cu" signal "L07_GND3")
		(16 "In7.Cu" signal "L08_SIG2")
		(18 "In8.Cu" signal "L09_GND4")
		(2 "B.Cu" signal "BOTTOM")
		(9 "F.Adhes" user "F.Adhesive")
		(11 "B.Adhes" user "B.Adhesive")
		(13 "F.Paste" user "Package Geometry/Pastemask Top")
		(15 "B.Paste" user "Package Geometry/Pastemask Bottom")
		(5 "F.SilkS" user "Ref Des/Silkscreen Top")
		(7 "B.SilkS" user "Ref Des/Silkscreen Bottom")
		(1 "F.Mask" user "Board Geometry/Soldermask Top")
		(3 "B.Mask" user "Board Geometry/Soldermask Bottom")
		(17 "Dwgs.User" user "User.Drawings")
		(19 "Cmts.User" user "User.Comments")
		(21 "Eco1.User" user "User.Eco1")
		(23 "Eco2.User" user "User.Eco2")
		(25 "Edge.Cuts" user "Board Geometry/Outline")
		(27 "Margin" user)
		(31 "F.CrtYd" user "Package Geometry/Place Bound Top")
		(29 "B.CrtYd" user "Package Geometry/Place Bound Bottom")
		(35 "F.Fab" user "Ref Des/Assembly Top")
		(33 "B.Fab" user "Ref Des/Assembly Bottom")
	)
	(footprint ""
		(layer "F.Cu")
		(at 87.249 -64.3128 90)
		(property "Reference" "C281"
			(at 13.2842 -9.61263 90)
			(unlocked yes)
			(layer "F.SilkS")
			(effects
				(font
					(size 0.7874 0.5842)
					(thickness 0.1524)
				)
			)
		)
		(property "Value" "VAL*"
			(at 0.0762 2.067306 90)
			(unlocked yes)
			(layer "F.Fab")
			(hide yes)
			(effects
				(font
					(size 0.7874 0.5842)
					(thickness 0.1524)
				)
			)
		)
		(property "Device Type" "CAPACITOR-G105-0B104-EK,0.1UF,A"
			(at 0.0508 1.127506 90)
			(unlocked yes)
			(layer "F.Fab")
			(hide yes)
			(effects
				(font
					(size 0.7874 0.5842)
					(thickness 0.1524)
				)
			)
		)
		(property "User Part Number" "PARTNUM*"
			(at 0.1016 4.023106 90)
			(unlocked yes)
			(layer "Cmts.User")
			(hide yes)
			(effects
				(font
					(size 0.7874 0.5842)
					(thickness 0.1524)
				)
			)
		)
		(property "Tolerance" "TOL*"
			(at 0.0762 3.032506 90)
			(unlocked yes)
			(layer "Cmts.User")
			(hide yes)
			(effects
				(font
					(size 0.7874 0.5842)
					(thickness 0.1524)
				)
			)
		)
		(duplicate_pad_numbers_are_jumpers no)
		(fp_line
			(start 1.143 -0.5588)
			(end -1.143 -0.5588)
			(stroke
				(width 0.1)
				(type default)
			)
			(layer "F.SilkS")
		)
		(fp_line
			(start -1.143 -0.5588)
			(end -1.143 0.5588)
			(stroke
				(width 0.1)
				(type default)
			)
			(layer "F.SilkS")
		)
		(fp_line
			(start 1.143 0.5588)
			(end 1.143 -0.5588)
			(stroke
				(width 0.1)
				(type default)
			)
			(layer "F.SilkS")
		)
		(fp_line
			(start -1.143 0.5588)
			(end 1.143 0.5588)
			(stroke
				(width 0.1)
				(type default)
			)
			(layer "F.SilkS")
		)
		(fp_rect
			(start -1.143 -0.5588)
			(end 1.143 0.5588)
			(stroke
				(width 0)
				(type default)
			)
			(fill no)
			(layer "F.CrtYd")
		)
		(fp_line
			(start 0.508 -0.3048)
			(end -0.508 -0.3048)
			(stroke
				(width 0.1)
				(type default)
			)
			(layer "F.Fab")
		)
		(fp_line
			(start -0.508 -0.3048)
			(end -0.508 0.3048)
			(stroke
				(width 0.1)
				(type default)
			)
			(layer "F.Fab")
		)
		(fp_line
			(start 0.508 0.3048)
			(end 0.508 -0.3048)
			(stroke
				(width 0.1)
				(type default)
			)
			(layer "F.Fab")
		)
		(fp_line
			(start -0.508 0.3048)
			(end 0.508 0.3048)
			(stroke
				(width 0.1)
				(type default)
			)
			(layer "F.Fab")
		)
		(pad "1" smd rect
			(at -0.5334 0 90)
			(size 0.7112 0.6096)
			(layers "F.Cu" "F.Mask" "F.Paste")
			(net "VDD_BNO085")
		)
		(pad "2" smd rect
			(at 0.5334 0 90)
			(size 0.7112 0.6096)
			(layers "F.Cu" "F.Mask" "F.Paste")
			(net "SG")
		)
		(zone
			(layer "F.Cu")
			(hatch none 0.5)
			(connect_pads
				(clearance 0)
			)
			(min_thickness 0.25)
			(keepout
				(tracks allowed)
				(vias not_allowed)
				(pads allowed)
				(copperpour not_allowed)
				(footprints allowed)
			)
			(placement
				(enabled no)
				(sheetname "")
			)
			(fill
				(thermal_gap 0.5)
				(thermal_bridge_width 0.5)
				(island_removal_mode 0)
			)
			(polygon
				(pts
					(xy 86.9442 -64.2366) (xy 87.5538 -64.2366) (xy 87.5538 -64.389) (xy 86.9442 -64.389)
				)
			)
		)
	)
	(footprint ""
		(layer "F.Cu")
		(at 49.784 -131.572)
		(property "Reference" "SP52"
			(at 0 0 0)
			(layer "F.SilkS")
			(hide yes)
			(effects
				(font
					(size 1.27 1.27)
				)
			)
		)
		(property "Value" ""
			(at 0 0 0)
			(layer "F.Fab")
			(effects
				(font
					(size 1.27 1.27)
				)
			)
		)
		(duplicate_pad_numbers_are_jumpers no)
	)
	(footprint ""
		(layer "F.Cu")
		(at 41.656 -80.518 180)
		(property "Reference" "CR2"
			(at 0.635 4.40563 0)
			(unlocked yes)
			(layer "F.SilkS")
			(effects
				(font
					(size 0.7874 0.5842)
					(thickness 0.1524)
				)
			)
		)
		(property "Value" ""
			(at 0 0 180)
			(layer "F.Fab")
			(effects
				(font
					(size 1.27 1.27)
				)
			)
		)
		(property "Device Type" "DIODE_2F-G122-10186-01"
			(at 0 2.037842 180)
			(unlocked yes)
			(layer "F.Fab")
			(hide yes)
			(effects
				(font
					(size 0.7874 0.5842)
					(thickness 0.000001)
				)
			)
		)
		(property "User Part Number" "PARTNUM*"
			(at 0 3.231642 180)
			(unlocked yes)
			(layer "Cmts.User")
			(hide yes)
			(effects
				(font
					(size 0.7874 0.5842)
					(thickness 0.000001)
				)
			)
		)
		(duplicate_pad_numbers_are_jumpers no)
		(fp_line
			(start 1.608074 0.928878)
			(end -1.608074 0.928878)
			(stroke
				(width 0.1)
				(type default)
			)
			(layer "F.SilkS")
		)
		(fp_line
			(start 1.608074 -0.928878)
			(end 1.608074 0.928878)
			(stroke
				(width 0.1)
				(type default)
			)
			(layer "F.SilkS")
		)
		(fp_line
			(start -1.608074 0.928878)
			(end -1.608074 -0.928878)
			(stroke
				(width 0.1)
				(type default)
			)
			(layer "F.SilkS")
		)
		(fp_line
			(start -1.608074 -0.928878)
			(end 1.608074 -0.928878)
			(stroke
				(width 0.1)
				(type default)
			)
			(layer "F.SilkS")
		)
		(fp_poly
			(pts
				(xy -2.116074 -0.928878) (xy -2.116074 0.928878) (xy -1.608074 0.928878) (xy -1.608074 -0.928878)
			)
			(stroke
				(width 0)
				(type default)
			)
			(fill yes)
			(layer "F.SilkS")
		)
		(fp_poly
			(pts
				(xy -2.116074 1.182878) (xy 1.862074 1.182878) (xy 1.862074 -1.182878) (xy -2.116074 -1.182878)
			)
			(stroke
				(width 0)
				(type default)
			)
			(fill no)
			(layer "F.CrtYd")
		)
		(fp_line
			(start 0.899922 0.674878)
			(end -0.899922 0.674878)
			(stroke
				(width 0.1)
				(type default)
			)
			(layer "F.Fab")
		)
		(fp_line
			(start 0.899922 -0.674878)
			(end 0.899922 0.674878)
			(stroke
				(width 0.1)
				(type default)
			)
			(layer "F.Fab")
		)
		(fp_line
			(start -0.899922 0.674878)
			(end -0.899922 -0.674878)
			(stroke
				(width 0.1)
				(type default)
			)
			(layer "F.Fab")
		)
		(fp_line
			(start -0.899922 -0.674878)
			(end 0.899922 -0.674878)
			(stroke
				(width 0.1)
				(type default)
			)
			(layer "F.Fab")
		)
		(fp_poly
			(pts
				(xy -0.899922 -0.674878) (xy -0.899922 0.674878) (xy -0.391922 0.674878) (xy -0.391922 -0.674878)
			)
			(stroke
				(width 0)
				(type default)
			)
			(fill yes)
			(layer "F.Fab")
		)
		(fp_text user "A"
			(at 2.413 0.59563 0)
			(unlocked yes)
			(layer "F.SilkS")
			(effects
				(font
					(size 0.7874 0.5842)
					(thickness 0.1524)
				)
			)
		)
		(fp_text user "C"
			(at -2.032 -1.68275 0)
			(unlocked yes)
			(layer "F.SilkS")
			(effects
				(font
					(size 0.635 0.4064)
					(thickness 0.1524)
				)
			)
		)
		(fp_text user "A"
			(at 2.262124 0.156718 0)
			(unlocked yes)
			(layer "F.Fab")
			(effects
				(font
					(size 0.7874 0.5842)
					(thickness 0.1524)
				)
			)
		)
		(fp_text user "C"
			(at -1.778 0.97663 0)
			(unlocked yes)
			(layer "F.Fab")
			(effects
				(font
					(size 0.7874 0.5842)
					(thickness 0.1524)
				)
			)
		)
		(pad "A" smd rect
			(at 1.100074 0 180)
			(size 0.508 0.508)
			(layers "F.Cu" "F.Mask" "F.Paste")
			(net "XP5R0V_FT4232")
		)
		(pad "C" smd rect
			(at -1.100074 0 180)
			(size 0.508 0.508)
			(layers "F.Cu" "F.Mask" "F.Paste")
			(net "UNNAMED_525_CAPACITOR_I7_1")
		)
	)
	(footprint ""
		(layer "F.Cu")
		(at 57.531 -129.54)
		(property "Reference" "SP58"
			(at 0 0 0)
			(layer "F.SilkS")
			(hide yes)
			(effects
				(font
					(size 1.27 1.27)
				)
			)
		)
		(property "Value" ""
			(at 0 0 0)
			(layer "F.Fab")
			(effects
				(font
					(size 1.27 1.27)
				)
			)
		)
		(duplicate_pad_numbers_are_jumpers no)
	)
)
